(kicad_pcb
	(version 20260206)
	(generator "pcbnew")
	(generator_version "10.0")
	(general
		(thickness 1.6)
		(legacy_teardrops no)
	)
	(paper "A4")
	(title_block
		(title "03242023_DA0F0TMBIJ0_F0T_Motherboard_J_brd_V01_OCP.brd")
		(comment 1 "Grand Teton / footprints 4298-4303 of 6105")
	)
	(layers
		(0 "F.Cu" signal "TOP")
		(4 "In1.Cu" signal "GND")
		(6 "In2.Cu" signal "IN1")
		(8 "In3.Cu" signal "GND1")
		(10 "In4.Cu" signal "IN2")
		(12 "In5.Cu" signal "GND2")
		(14 "In6.Cu" signal "IN3")
		(16 "In7.Cu" signal "GND3")
		(18 "In8.Cu" signal "VCC")
		(20 "In9.Cu" signal "VCC1")
		(22 "In10.Cu" signal "GND4")
		(24 "In11.Cu" signal "IN4")
		(26 "In12.Cu" signal "GND5")
		(28 "In13.Cu" signal "IN5")
		(30 "In14.Cu" signal "GND6")
		(32 "In15.Cu" signal "IN6")
		(34 "In16.Cu" signal "GND7")
		(2 "B.Cu" signal "BOTTOM")
		(9 "F.Adhes" user "F.Adhesive")
		(11 "B.Adhes" user "B.Adhesive")
		(13 "F.Paste" user "Package Geometry/Pastemask Top")
		(15 "B.Paste" user "Package Geometry/Pastemask Bottom")
		(5 "F.SilkS" user "Ref Des/Silkscreen Top")
		(7 "B.SilkS" user "Ref Des/Silkscreen Bottom")
		(1 "F.Mask" user "Board Geometry/Soldermask Top")
		(3 "B.Mask" user "Board Geometry/Soldermask Bottom")
		(17 "Dwgs.User" user "User.Drawings")
		(19 "Cmts.User" user "User.Comments")
		(21 "Eco1.User" user "User.Eco1")
		(23 "Eco2.User" user "User.Eco2")
		(25 "Edge.Cuts" user "Board Geometry/Outline")
		(27 "Margin" user)
		(31 "F.CrtYd" user "Package Geometry/Place Bound Top")
		(29 "B.CrtYd" user "Package Geometry/Place Bound Bottom")
		(35 "F.Fab" user "Ref Des/Assembly Top")
		(33 "B.Fab" user "Ref Des/Assembly Bottom")
	)
	(footprint ""
		(layer "B.Cu")
		(at 138.5443 -22.943058 90)
		(property "Reference" "R4467"
			(at 0 0 90)
			(layer "B.SilkS")
			(hide yes)
			(effects
				(font
					(size 1.27 1.27)
				)
				(justify mirror)
			)
		)
		(property "Value" ""
			(at 0 0 90)
			(layer "B.Fab")
			(effects
				(font
					(size 1.27 1.27)
				)
				(justify mirror)
			)
		)
		(duplicate_pad_numbers_are_jumpers no)
		(fp_line
			(start 0.44323 -0.4064)
			(end -0.41275 -0.4064)
			(stroke
				(width 0.1524)
				(type default)
			)
			(layer "B.SilkS")
		)
		(fp_line
			(start -0.7874 -0.11938)
			(end -0.7874 0.4064)
			(stroke
				(width 0.1524)
				(type default)
			)
			(layer "B.SilkS")
		)
		(fp_line
			(start 0.7874 0.4064)
			(end 0.7874 0.04318)
			(stroke
				(width 0.1524)
				(type default)
			)
			(layer "B.SilkS")
		)
		(fp_line
			(start -0.7874 0.4064)
			(end 0.7874 0.4064)
			(stroke
				(width 0.1524)
				(type default)
			)
			(layer "B.SilkS")
		)
		(fp_line
			(start 0.67945 -0.305054)
			(end 0.12065 -0.305054)
			(stroke
				(width 0.1)
				(type default)
			)
			(layer "B.Fab")
		)
		(fp_line
			(start 0.12065 -0.305054)
			(end 0.12065 -0.2794)
			(stroke
				(width 0.1)
				(type default)
			)
			(layer "B.Fab")
		)
		(fp_line
			(start -0.12065 -0.3048)
			(end -0.67945 -0.3048)
			(stroke
				(width 0.1)
				(type default)
			)
			(layer "B.Fab")
		)
		(fp_line
			(start -0.67945 -0.3048)
			(end -0.67945 0.3048)
			(stroke
				(width 0.1)
				(type default)
			)
			(layer "B.Fab")
		)
		(fp_line
			(start 0.12065 -0.2794)
			(end -0.12065 -0.2794)
			(stroke
				(width 0.1)
				(type default)
			)
			(layer "B.Fab")
		)
		(fp_line
			(start -0.12065 -0.2794)
			(end -0.12065 -0.3048)
			(stroke
				(width 0.1)
				(type default)
			)
			(layer "B.Fab")
		)
		(fp_line
			(start 0.12065 0.2794)
			(end 0.12065 0.3048)
			(stroke
				(width 0.1)
				(type default)
			)
			(layer "B.Fab")
		)
		(fp_line
			(start -0.120396 0.2794)
			(end 0.12065 0.2794)
			(stroke
				(width 0.1)
				(type default)
			)
			(layer "B.Fab")
		)
		(fp_line
			(start 0.67945 0.3048)
			(end 0.67945 -0.305054)
			(stroke
				(width 0.1)
				(type default)
			)
			(layer "B.Fab")
		)
		(fp_line
			(start 0.12065 0.3048)
			(end 0.67945 0.3048)
			(stroke
				(width 0.1)
				(type default)
			)
			(layer "B.Fab")
		)
		(fp_line
			(start -0.120396 0.3048)
			(end -0.120396 0.2794)
			(stroke
				(width 0.1)
				(type default)
			)
			(layer "B.Fab")
		)
		(fp_line
			(start -0.67945 0.3048)
			(end -0.120396 0.3048)
			(stroke
				(width 0.1)
				(type default)
			)
			(layer "B.Fab")
		)
		(pad "1" smd circle
			(at 0.40005 0 270)
			(size 0 0)
			(layers "B.Cu" "B.Mask" "B.Paste")
			(net "USB2_HUB_2_BUF_EXT_R_DP")
		)
		(pad "2" smd circle
			(at -0.40005 0 270)
			(size 0 0)
			(layers "B.Cu" "B.Mask" "B.Paste")
			(net "USB2_HUB_2_BUF_EXT_DP")
		)
	)
	(footprint ""
		(layer "B.Cu")
		(at 454.077324 -13.09116 90)
		(property "Reference" "R429"
			(at 0 0 90)
			(layer "B.SilkS")
			(hide yes)
			(effects
				(font
					(size 1.27 1.27)
				)
				(justify mirror)
			)
		)
		(property "Value" ""
			(at 0 0 90)
			(layer "B.Fab")
			(effects
				(font
					(size 1.27 1.27)
				)
				(justify mirror)
			)
		)
		(duplicate_pad_numbers_are_jumpers no)
		(fp_line
			(start 0.7874 -0.4064)
			(end -0.7874 -0.4064)
			(stroke
				(width 0.1524)
				(type default)
			)
			(layer "B.SilkS")
		)
		(fp_line
			(start -0.7874 -0.4064)
			(end -0.7874 0.4064)
			(stroke
				(width 0.1524)
				(type default)
			)
			(layer "B.SilkS")
		)
		(fp_line
			(start 0.7874 0.4064)
			(end 0.7874 -0.4064)
			(stroke
				(width 0.1524)
				(type default)
			)
			(layer "B.SilkS")
		)
		(fp_line
			(start -0.7874 0.4064)
			(end 0.7874 0.4064)
			(stroke
				(width 0.1524)
				(type default)
			)
			(layer "B.SilkS")
		)
		(fp_line
			(start 0.67945 -0.305054)
			(end 0.12065 -0.305054)
			(stroke
				(width 0.1)
				(type default)
			)
			(layer "B.Fab")
		)
		(fp_line
			(start 0.12065 -0.305054)
			(end 0.12065 -0.2794)
			(stroke
				(width 0.1)
				(type default)
			)
			(layer "B.Fab")
		)
		(fp_line
			(start -0.12065 -0.3048)
			(end -0.67945 -0.3048)
			(stroke
				(width 0.1)
				(type default)
			)
			(layer "B.Fab")
		)
		(fp_line
			(start -0.67945 -0.3048)
			(end -0.67945 0.3048)
			(stroke
				(width 0.1)
				(type default)
			)
			(layer "B.Fab")
		)
		(fp_line
			(start 0.12065 -0.2794)
			(end -0.12065 -0.2794)
			(stroke
				(width 0.1)
				(type default)
			)
			(layer "B.Fab")
		)
		(fp_line
			(start -0.12065 -0.2794)
			(end -0.12065 -0.3048)
			(stroke
				(width 0.1)
				(type default)
			)
			(layer "B.Fab")
		)
		(fp_line
			(start 0.12065 0.2794)
			(end 0.12065 0.3048)
			(stroke
				(width 0.1)
				(type default)
			)
			(layer "B.Fab")
		)
		(fp_line
			(start -0.120396 0.2794)
			(end 0.12065 0.2794)
			(stroke
				(width 0.1)
				(type default)
			)
			(layer "B.Fab")
		)
		(fp_line
			(start 0.67945 0.3048)
			(end 0.67945 -0.305054)
			(stroke
				(width 0.1)
				(type default)
			)
			(layer "B.Fab")
		)
		(fp_line
			(start 0.12065 0.3048)
			(end 0.67945 0.3048)
			(stroke
				(width 0.1)
				(type default)
			)
			(layer "B.Fab")
		)
		(fp_line
			(start -0.120396 0.3048)
			(end -0.120396 0.2794)
			(stroke
				(width 0.1)
				(type default)
			)
			(layer "B.Fab")
		)
		(fp_line
			(start -0.67945 0.3048)
			(end -0.120396 0.3048)
			(stroke
				(width 0.1)
				(type default)
			)
			(layer "B.Fab")
		)
		(pad "1" smd circle
			(at 0.40005 0 270)
			(size 0 0)
			(layers "B.Cu" "B.Mask" "B.Paste")
			(net "OCP_SFF_MAIN_PWR_EN")
		)
		(pad "2" smd circle
			(at -0.40005 0 270)
			(size 0 0)
			(layers "B.Cu" "B.Mask" "B.Paste")
			(net "OCP_SFF_MAIN_PWR_EN_R")
		)
	)
	(footprint ""
		(layer "B.Cu")
		(at 75.363324 -190.705232 -90)
		(property "Reference" "R63"
			(at 0 0 90)
			(layer "B.SilkS")
			(hide yes)
			(effects
				(font
					(size 1.27 1.27)
				)
				(justify mirror)
			)
		)
		(property "Value" ""
			(at 0 0 90)
			(layer "B.Fab")
			(effects
				(font
					(size 1.27 1.27)
				)
				(justify mirror)
			)
		)
		(duplicate_pad_numbers_are_jumpers no)
		(fp_line
			(start -0.7874 0.4064)
			(end 0.7874 0.4064)
			(stroke
				(width 0.1524)
				(type default)
			)
			(layer "B.SilkS")
		)
		(fp_line
			(start 0.7874 0.4064)
			(end 0.7874 -0.4064)
			(stroke
				(width 0.1524)
				(type default)
			)
			(layer "B.SilkS")
		)
		(fp_line
			(start -0.7874 -0.4064)
			(end -0.7874 0.4064)
			(stroke
				(width 0.1524)
				(type default)
			)
			(layer "B.SilkS")
		)
		(fp_line
			(start 0.7874 -0.4064)
			(end -0.7874 -0.4064)
			(stroke
				(width 0.1524)
				(type default)
			)
			(layer "B.SilkS")
		)
		(fp_line
			(start -0.67945 0.3048)
			(end -0.120396 0.3048)
			(stroke
				(width 0.1)
				(type default)
			)
			(layer "B.Fab")
		)
		(fp_line
			(start -0.120396 0.3048)
			(end -0.120396 0.2794)
			(stroke
				(width 0.1)
				(type default)
			)
			(layer "B.Fab")
		)
		(fp_line
			(start 0.12065 0.3048)
			(end 0.67945 0.3048)
			(stroke
				(width 0.1)
				(type default)
			)
			(layer "B.Fab")
		)
		(fp_line
			(start 0.67945 0.3048)
			(end 0.67945 -0.305054)
			(stroke
				(width 0.1)
				(type default)
			)
			(layer "B.Fab")
		)
		(fp_line
			(start -0.120396 0.2794)
			(end 0.12065 0.2794)
			(stroke
				(width 0.1)
				(type default)
			)
			(layer "B.Fab")
		)
		(fp_line
			(start 0.12065 0.2794)
			(end 0.12065 0.3048)
			(stroke
				(width 0.1)
				(type default)
			)
			(layer "B.Fab")
		)
		(fp_line
			(start -0.12065 -0.2794)
			(end -0.12065 -0.3048)
			(stroke
				(width 0.1)
				(type default)
			)
			(layer "B.Fab")
		)
		(fp_line
			(start 0.12065 -0.2794)
			(end -0.12065 -0.2794)
			(stroke
				(width 0.1)
				(type default)
			)
			(layer "B.Fab")
		)
		(fp_line
			(start -0.67945 -0.3048)
			(end -0.67945 0.3048)
			(stroke
				(width 0.1)
				(type default)
			)
			(layer "B.Fab")
		)
		(fp_line
			(start -0.12065 -0.3048)
			(end -0.67945 -0.3048)
			(stroke
				(width 0.1)
				(type default)
			)
			(layer "B.Fab")
		)
		(fp_line
			(start 0.12065 -0.305054)
			(end 0.12065 -0.2794)
			(stroke
				(width 0.1)
				(type default)
			)
			(layer "B.Fab")
		)
		(fp_line
			(start 0.67945 -0.305054)
			(end 0.12065 -0.305054)
			(stroke
				(width 0.1)
				(type default)
			)
			(layer "B.Fab")
		)
		(pad "1" smd circle
			(at 0.40005 0 90)
			(size 0 0)
			(layers "B.Cu" "B.Mask" "B.Paste")
			(net "PECI_CPU_GTL")
		)
		(pad "2" smd circle
			(at -0.40005 0 90)
			(size 0 0)
			(layers "B.Cu" "B.Mask" "B.Paste")
			(net "PECI_CPU1_GTL_R")
		)
	)
	(footprint ""
		(layer "B.Cu")
		(at 155.18638 -13.764768 90)
		(property "Reference" "R2414"
			(at 0 0 90)
			(layer "B.SilkS")
			(hide yes)
			(effects
				(font
					(size 1.27 1.27)
				)
				(justify mirror)
			)
		)
		(property "Value" ""
			(at 0 0 90)
			(layer "B.Fab")
			(effects
				(font
					(size 1.27 1.27)
				)
				(justify mirror)
			)
		)
		(duplicate_pad_numbers_are_jumpers no)
		(fp_line
			(start 0.7874 -0.4064)
			(end -0.7874 -0.4064)
			(stroke
				(width 0.1524)
				(type default)
			)
			(layer "B.SilkS")
		)
		(fp_line
			(start -0.7874 -0.4064)
			(end -0.7874 0.4064)
			(stroke
				(width 0.1524)
				(type default)
			)
			(layer "B.SilkS")
		)
		(fp_line
			(start 0.7874 0.4064)
			(end 0.7874 -0.4064)
			(stroke
				(width 0.1524)
				(type default)
			)
			(layer "B.SilkS")
		)
		(fp_line
			(start -0.7874 0.4064)
			(end 0.7874 0.4064)
			(stroke
				(width 0.1524)
				(type default)
			)
			(layer "B.SilkS")
		)
		(fp_line
			(start 0.67945 -0.305054)
			(end 0.12065 -0.305054)
			(stroke
				(width 0.1)
				(type default)
			)
			(layer "B.Fab")
		)
		(fp_line
			(start 0.12065 -0.305054)
			(end 0.12065 -0.2794)
			(stroke
				(width 0.1)
				(type default)
			)
			(layer "B.Fab")
		)
		(fp_line
			(start -0.12065 -0.3048)
			(end -0.67945 -0.3048)
			(stroke
				(width 0.1)
				(type default)
			)
			(layer "B.Fab")
		)
		(fp_line
			(start -0.67945 -0.3048)
			(end -0.67945 0.3048)
			(stroke
				(width 0.1)
				(type default)
			)
			(layer "B.Fab")
		)
		(fp_line
			(start 0.12065 -0.2794)
			(end -0.12065 -0.2794)
			(stroke
				(width 0.1)
				(type default)
			)
			(layer "B.Fab")
		)
		(fp_line
			(start -0.12065 -0.2794)
			(end -0.12065 -0.3048)
			(stroke
				(width 0.1)
				(type default)
			)
			(layer "B.Fab")
		)
		(fp_line
			(start 0.12065 0.2794)
			(end 0.12065 0.3048)
			(stroke
				(width 0.1)
				(type default)
			)
			(layer "B.Fab")
		)
		(fp_line
			(start -0.120396 0.2794)
			(end 0.12065 0.2794)
			(stroke
				(width 0.1)
				(type default)
			)
			(layer "B.Fab")
		)
		(fp_line
			(start 0.67945 0.3048)
			(end 0.67945 -0.305054)
			(stroke
				(width 0.1)
				(type default)
			)
			(layer "B.Fab")
		)
		(fp_line
			(start 0.12065 0.3048)
			(end 0.67945 0.3048)
			(stroke
				(width 0.1)
				(type default)
			)
			(layer "B.Fab")
		)
		(fp_line
			(start -0.120396 0.3048)
			(end -0.120396 0.2794)
			(stroke
				(width 0.1)
				(type default)
			)
			(layer "B.Fab")
		)
		(fp_line
			(start -0.67945 0.3048)
			(end -0.120396 0.3048)
			(stroke
				(width 0.1)
				(type default)
			)
			(layer "B.Fab")
		)
		(pad "1" smd circle
			(at 0.40005 0 270)
			(size 0 0)
			(layers "B.Cu" "B.Mask" "B.Paste")
			(net "SMB_2_BMC_GPU_SDA")
		)
		(pad "2" smd circle
			(at -0.40005 0 270)
			(size 0 0)
			(layers "B.Cu" "B.Mask" "B.Paste")
			(net "SMB_PCIE2_3V3AUX_SDA_R0")
		)
	)
	(footprint ""
		(layer "B.Cu")
		(at 121.782078 -355.194108)
		(property "Reference" "C2445"
			(at 0 0 0)
			(layer "B.SilkS")
			(hide yes)
			(effects
				(font
					(size 1.27 1.27)
				)
				(justify mirror)
			)
		)
		(property "Value" ""
			(at 0 0 0)
			(layer "B.Fab")
			(effects
				(font
					(size 1.27 1.27)
				)
				(justify mirror)
			)
		)
		(duplicate_pad_numbers_are_jumpers no)
		(fp_line
			(start -0.7874 -0.4064)
			(end -0.7874 0.4064)
			(stroke
				(width 0.1524)
				(type default)
			)
			(layer "B.SilkS")
		)
		(fp_line
			(start -0.7874 0.4064)
			(end 0.7874 0.4064)
			(stroke
				(width 0.1524)
				(type default)
			)
			(layer "B.SilkS")
		)
		(fp_line
			(start 0.7874 -0.4064)
			(end -0.7874 -0.4064)
			(stroke
				(width 0.1524)
				(type default)
			)
			(layer "B.SilkS")
		)
		(fp_line
			(start 0.7874 0.4064)
			(end 0.7874 -0.4064)
			(stroke
				(width 0.1524)
				(type default)
			)
			(layer "B.SilkS")
		)
		(fp_line
			(start -0.67945 -0.3048)
			(end -0.67945 0.3048)
			(stroke
				(width 0.1)
				(type default)
			)
			(layer "B.Fab")
		)
		(fp_line
			(start -0.67945 0.3048)
			(end -0.120396 0.3048)
			(stroke
				(width 0.1)
				(type default)
			)
			(layer "B.Fab")
		)
		(fp_line
			(start -0.12065 -0.3048)
			(end -0.67945 -0.3048)
			(stroke
				(width 0.1)
				(type default)
			)
			(layer "B.Fab")
		)
		(fp_line
			(start -0.12065 -0.2794)
			(end -0.12065 -0.3048)
			(stroke
				(width 0.1)
				(type default)
			)
			(layer "B.Fab")
		)
		(fp_line
			(start -0.120396 0.2794)
			(end 0.12065 0.2794)
			(stroke
				(width 0.1)
				(type default)
			)
			(layer "B.Fab")
		)
		(fp_line
			(start -0.120396 0.3048)
			(end -0.120396 0.2794)
			(stroke
				(width 0.1)
				(type default)
			)
			(layer "B.Fab")
		)
		(fp_line
			(start 0.12065 -0.305054)
			(end 0.12065 -0.2794)
			(stroke
				(width 0.1)
				(type default)
			)
			(layer "B.Fab")
		)
		(fp_line
			(start 0.12065 -0.2794)
			(end -0.12065 -0.2794)
			(stroke
				(width 0.1)
				(type default)
			)
			(layer "B.Fab")
		)
		(fp_line
			(start 0.12065 0.2794)
			(end 0.12065 0.3048)
			(stroke
				(width 0.1)
				(type default)
			)
			(layer "B.Fab")
		)
		(fp_line
			(start 0.12065 0.3048)
			(end 0.67945 0.3048)
			(stroke
				(width 0.1)
				(type default)
			)
			(layer "B.Fab")
		)
		(fp_line
			(start 0.67945 -0.305054)
			(end 0.12065 -0.305054)
			(stroke
				(width 0.1)
				(type default)
			)
			(layer "B.Fab")
		)
		(fp_line
			(start 0.67945 0.3048)
			(end 0.67945 -0.305054)
			(stroke
				(width 0.1)
				(type default)
			)
			(layer "B.Fab")
		)
		(pad "1" smd circle
			(at 0.40005 0 180)
			(size 0 0)
			(layers "B.Cu" "B.Mask" "B.Paste")
			(net "FM_PVPP_HBM_CPU1_EN")
		)
		(pad "2" smd circle
			(at -0.40005 0 180)
			(size 0 0)
			(layers "B.Cu" "B.Mask" "B.Paste")
			(net "GND")
		)
	)
	(footprint ""
		(layer "B.Cu")
		(at 355.826822 -212.049614 180)
		(property "Reference" "C504"
			(at 0 0 0)
			(layer "B.SilkS")
			(hide yes)
			(effects
				(font
					(size 1.27 1.27)
				)
				(justify mirror)
			)
		)
		(property "Value" ""
			(at 0 0 0)
			(layer "B.Fab")
			(effects
				(font
					(size 1.27 1.27)
				)
				(justify mirror)
			)
		)
		(duplicate_pad_numbers_are_jumpers no)
		(fp_line
			(start 1.524 0.762)
			(end 1.524 -0.762)
			(stroke
				(width 0.1524)
				(type default)
			)
			(layer "B.SilkS")
		)
		(fp_line
			(start 1.524 -0.762)
			(end -1.524 -0.762)
			(stroke
				(width 0.1524)
				(type default)
			)
			(layer "B.SilkS")
		)
		(fp_line
			(start -1.524 0.762)
			(end 1.524 0.762)
			(stroke
				(width 0.1524)
				(type default)
			)
			(layer "B.SilkS")
		)
		(fp_line
			(start -1.524 -0.762)
			(end -1.524 0.762)
			(stroke
				(width 0.1524)
				(type default)
			)
			(layer "B.SilkS")
		)
		(fp_line
			(start 1.1049 0.724916)
			(end -1.1049 0.724916)
			(stroke
				(width 0.1)
				(type default)
			)
			(layer "B.Fab")
		)
		(fp_line
			(start 1.1049 -0.724916)
			(end 1.1049 0.724916)
			(stroke
				(width 0.1)
				(type default)
			)
			(layer "B.Fab")
		)
		(fp_line
			(start -1.1049 0.724916)
			(end -1.1049 -0.724916)
			(stroke
				(width 0.1)
				(type default)
			)
			(layer "B.Fab")
		)
		(fp_line
			(start -1.1049 -0.724916)
			(end 1.1049 -0.724916)
			(stroke
				(width 0.1)
				(type default)
			)
			(layer "B.Fab")
		)
		(pad "1" smd rect
			(at 0.889 0 180)
			(size 1.016 1.27)
			(layers "B.Cu" "B.Mask" "B.Paste")
			(net "PVCCFA_EHV_CPU0")
		)
		(pad "2" smd rect
			(at -0.889 0 180)
			(size 1.016 1.27)
			(layers "B.Cu" "B.Mask" "B.Paste")
			(net "GND")
		)
	)
)
